(kicad_pcb
	(version 20260206)
	(generator "pcbnew")
	(generator_version "10.0")
	(general
		(thickness 1.6)
		(legacy_teardrops no)
	)
	(paper "A4")
	(title_block
		(title "peb — Lightning_PEB_BRD.brd")
		(comment 1 "Lightning (Wiwynn / Facebook NVMe JBOF) / footprints 15-22 of 2563")
	)
	(layers
		(0 "F.Cu" signal "TOP")
		(4 "In1.Cu" signal "L2GND")
		(6 "In2.Cu" signal "L3")
		(8 "In3.Cu" signal "L4VCC")
		(10 "In4.Cu" signal "L5VCC")
		(12 "In5.Cu" signal "L6")
		(14 "In6.Cu" signal "L7GND")
		(2 "B.Cu" signal "BOTTOM")
		(9 "F.Adhes" user "F.Adhesive")
		(11 "B.Adhes" user "B.Adhesive")
		(13 "F.Paste" user "Package Geometry/Pastemask Top")
		(15 "B.Paste" user "Package Geometry/Pastemask Bottom")
		(5 "F.SilkS" user "Ref Des/Silkscreen Top")
		(7 "B.SilkS" user "Ref Des/Silkscreen Bottom")
		(1 "F.Mask" user "Board Geometry/Soldermask Top")
		(3 "B.Mask" user "Board Geometry/Soldermask Bottom")
		(17 "Dwgs.User" user "User.Drawings")
		(19 "Cmts.User" user "User.Comments")
		(21 "Eco1.User" user "User.Eco1")
		(23 "Eco2.User" user "User.Eco2")
		(25 "Edge.Cuts" user "Board Geometry/Outline")
		(27 "Margin" user)
		(31 "F.CrtYd" user "Package Geometry/Place Bound Top")
		(29 "B.CrtYd" user "Package Geometry/Place Bound Bottom")
		(35 "F.Fab" user "Ref Des/Assembly Top")
		(33 "B.Fab" user "Ref Des/Assembly Bottom")
	)
	(footprint ""
		(layer "F.Cu")
		(at 331.216 -15.621)
		(property "Reference" "SR715"
			(at 0 0 0)
			(layer "F.SilkS")
			(hide yes)
			(effects
				(font
					(size 1.27 1.27)
				)
			)
		)
		(property "Value" "150R2F-1-GP"
			(at 0.064008 -3.993896 0)
			(unlocked yes)
			(layer "F.Fab")
			(hide yes)
			(effects
				(font
					(size 1.016 1.016)
					(thickness 0.1524)
				)
			)
		)
		(property "Device Type" "R402H16"
			(at 0.064008 -5.517896 0)
			(unlocked yes)
			(layer "F.Fab")
			(hide yes)
			(effects
				(font
					(size 1.016 1.016)
					(thickness 0.1524)
				)
			)
		)
		(duplicate_pad_numbers_are_jumpers no)
		(fp_line
			(start -0.508 -0.9398)
			(end -0.508 0.9398)
			(stroke
				(width 0.1524)
				(type default)
			)
			(layer "F.SilkS")
		)
		(fp_line
			(start 0.508 -0.9398)
			(end -0.508 -0.9398)
			(stroke
				(width 0.1524)
				(type default)
			)
			(layer "F.SilkS")
		)
		(fp_rect
			(start -0.508 0.9398)
			(end 0.508 -0.9398)
			(stroke
				(width 0)
				(type default)
			)
			(fill no)
			(layer "F.CrtYd")
		)
		(fp_rect
			(start -0.508 0.9398)
			(end 0.508 -0.9398)
			(stroke
				(width 0)
				(type default)
			)
			(fill no)
			(layer "F.Fab")
		)
		(pad "1" smd custom
			(at 0 -0.4445)
			(size 0.1397 0.1397)
			(layers "F.Cu" "F.Mask" "F.Paste")
			(net "P3V3_STBY")
			(options
				(clearance outline)
				(anchor circle)
			)
			(primitives
				(gr_poly
					(pts
						(arc
							(start -0.1778 -0.2794)
							(mid -0.249642 -0.249642)
							(end -0.2794 -0.1778)
						)
						(arc
							(start -0.2794 0.1778)
							(mid -0.249642 0.249642)
							(end -0.1778 0.2794)
						)
						(arc
							(start 0.1778 0.2794)
							(mid 0.249642 0.249642)
							(end 0.2794 0.1778)
						)
						(arc
							(start 0.2794 -0.1778)
							(mid 0.249642 -0.249642)
							(end 0.1778 -0.2794)
						)
					)
					(width 0)
					(fill yes)
				)
			)
		)
		(pad "2" smd custom
			(at 0 0.4445)
			(size 0.1397 0.1397)
			(layers "F.Cu" "F.Mask" "F.Paste")
			(net "LED_R_6")
			(options
				(clearance outline)
				(anchor circle)
			)
			(primitives
				(gr_poly
					(pts
						(arc
							(start -0.1778 -0.2794)
							(mid -0.249642 -0.249642)
							(end -0.2794 -0.1778)
						)
						(arc
							(start -0.2794 0.1778)
							(mid -0.249642 0.249642)
							(end -0.1778 0.2794)
						)
						(arc
							(start 0.1778 0.2794)
							(mid 0.249642 0.249642)
							(end 0.2794 0.1778)
						)
						(arc
							(start 0.2794 -0.1778)
							(mid 0.249642 -0.249642)
							(end 0.1778 -0.2794)
						)
					)
					(width 0)
					(fill yes)
				)
			)
		)
	)
	(footprint ""
		(layer "F.Cu")
		(at 11.684 -74.1934 -90)
		(property "Reference" "TP152"
			(at 0 0 270)
			(layer "F.SilkS")
			(hide yes)
			(effects
				(font
					(size 1.27 1.27)
				)
			)
		)
		(property "Value" "TPAD28-2-GP"
			(at -0.0127 -1.6637 270)
			(unlocked yes)
			(layer "F.Fab")
			(hide yes)
			(effects
				(font
					(size 1.016 1.016)
					(thickness 0.1524)
				)
			)
		)
		(property "Device Type" "TPAD28"
			(at -0.0127 -3.1877 270)
			(unlocked yes)
			(layer "F.Fab")
			(hide yes)
			(effects
				(font
					(size 1.016 1.016)
					(thickness 0.1524)
				)
			)
		)
		(duplicate_pad_numbers_are_jumpers no)
		(fp_poly
			(pts
				(arc
					(start 0 -0.3556)
					(mid 0 0.3556)
					(end 0 -0.3556)
				)
			)
			(stroke
				(width 0)
				(type default)
			)
			(fill no)
			(layer "F.CrtYd")
		)
		(fp_poly
			(pts
				(arc
					(start 0 -0.6096)
					(mid 0 0.6096)
					(end 0 -0.6096)
				)
			)
			(stroke
				(width 0)
				(type default)
			)
			(fill no)
			(layer "F.Fab")
		)
		(pad "1" smd circle
			(at 0 0 270)
			(size 0.7112 0.7112)
			(layers "F.Cu" "F.Mask" "F.Paste")
			(net "NCSI_ARB_IN")
		)
	)
	(footprint ""
		(layer "F.Cu")
		(at 23.876 -132.715 90)
		(property "Reference" "R347"
			(at 0 0 90)
			(layer "F.SilkS")
			(hide yes)
			(effects
				(font
					(size 1.27 1.27)
				)
			)
		)
		(property "Value" "3K3R2F-2-GP"
			(at 0.064008 -3.993896 90)
			(unlocked yes)
			(layer "F.Fab")
			(hide yes)
			(effects
				(font
					(size 1.016 1.016)
					(thickness 0.1524)
				)
			)
		)
		(property "Device Type" "R402H16"
			(at 0.064008 -5.517896 90)
			(unlocked yes)
			(layer "F.Fab")
			(hide yes)
			(effects
				(font
					(size 1.016 1.016)
					(thickness 0.1524)
				)
			)
		)
		(duplicate_pad_numbers_are_jumpers no)
		(fp_line
			(start 0.508 -0.9398)
			(end -0.508 -0.9398)
			(stroke
				(width 0.1524)
				(type default)
			)
			(layer "F.SilkS")
		)
		(fp_line
			(start -0.508 -0.9398)
			(end -0.508 0.9398)
			(stroke
				(width 0.1524)
				(type default)
			)
			(layer "F.SilkS")
		)
		(fp_rect
			(start -0.508 0.9398)
			(end 0.508 -0.9398)
			(stroke
				(width 0)
				(type default)
			)
			(fill no)
			(layer "F.CrtYd")
		)
		(fp_rect
			(start -0.508 0.9398)
			(end 0.508 -0.9398)
			(stroke
				(width 0)
				(type default)
			)
			(fill no)
			(layer "F.Fab")
		)
		(pad "1" smd custom
			(at 0 -0.4445 90)
			(size 0.1397 0.1397)
			(layers "F.Cu" "F.Mask" "F.Paste")
			(net "P3V3_STBY")
			(options
				(clearance outline)
				(anchor circle)
			)
			(primitives
				(gr_poly
					(pts
						(arc
							(start -0.1778 -0.2794)
							(mid -0.249642 -0.249642)
							(end -0.2794 -0.1778)
						)
						(arc
							(start -0.2794 0.1778)
							(mid -0.249642 0.249642)
							(end -0.1778 0.2794)
						)
						(arc
							(start 0.1778 0.2794)
							(mid 0.249642 0.249642)
							(end 0.2794 0.1778)
						)
						(arc
							(start 0.2794 -0.1778)
							(mid 0.249642 -0.249642)
							(end 0.1778 -0.2794)
						)
					)
					(width 0)
					(fill yes)
				)
			)
		)
		(pad "2" smd custom
			(at 0 0.4445 90)
			(size 0.1397 0.1397)
			(layers "F.Cu" "F.Mask" "F.Paste")
			(net "ROMA2")
			(options
				(clearance outline)
				(anchor circle)
			)
			(primitives
				(gr_poly
					(pts
						(arc
							(start -0.1778 -0.2794)
							(mid -0.249642 -0.249642)
							(end -0.2794 -0.1778)
						)
						(arc
							(start -0.2794 0.1778)
							(mid -0.249642 0.249642)
							(end -0.1778 0.2794)
						)
						(arc
							(start 0.1778 0.2794)
							(mid 0.249642 0.249642)
							(end 0.2794 0.1778)
						)
						(arc
							(start 0.2794 -0.1778)
							(mid 0.249642 -0.249642)
							(end 0.1778 -0.2794)
						)
					)
					(width 0)
					(fill yes)
				)
			)
		)
	)
	(footprint ""
		(layer "F.Cu")
		(at 63.591948 -212.420454 180)
		(property "Reference" "C357"
			(at 0 0 180)
			(layer "F.SilkS")
			(hide yes)
			(effects
				(font
					(size 1.27 1.27)
				)
			)
		)
		(property "Value" "SCD22U10V2KX-1GP"
			(at 1.1811 -2.7051 180)
			(unlocked yes)
			(layer "F.Fab")
			(hide yes)
			(effects
				(font
					(size 1.016 1.016)
					(thickness 0.1524)
				)
			)
		)
		(property "Device Type" "C402H22"
			(at 1.1811 -4.2291 180)
			(unlocked yes)
			(layer "F.Fab")
			(hide yes)
			(effects
				(font
					(size 1.016 1.016)
					(thickness 0.1524)
				)
			)
		)
		(duplicate_pad_numbers_are_jumpers no)
		(fp_rect
			(start -0.4318 0.9525)
			(end 0.4318 -0.9525)
			(stroke
				(width 0)
				(type default)
			)
			(fill no)
			(layer "F.CrtYd")
		)
		(fp_rect
			(start -0.4318 0.9525)
			(end 0.4318 -0.9525)
			(stroke
				(width 0)
				(type default)
			)
			(fill no)
			(layer "F.Fab")
		)
		(pad "1" smd custom
			(at 0 -0.4445 180)
			(size 0.1524 0.1524)
			(layers "F.Cu" "F.Mask" "F.Paste")
			(net "PCIE_TX_CAP_P71")
			(options
				(clearance outline)
				(anchor circle)
			)
			(primitives
				(gr_poly
					(pts
						(arc
							(start 0.3048 -0.2032)
							(mid 0.275042 -0.275042)
							(end 0.2032 -0.3048)
						)
						(arc
							(start -0.2032 -0.3048)
							(mid -0.275042 -0.275042)
							(end -0.3048 -0.2032)
						)
						(arc
							(start -0.3048 0.2032)
							(mid -0.275042 0.275042)
							(end -0.2032 0.3048)
						)
						(arc
							(start 0.2032 0.3048)
							(mid 0.275042 0.275042)
							(end 0.3048 0.2032)
						)
					)
					(width 0)
					(fill yes)
				)
			)
		)
		(pad "2" smd custom
			(at 0 0.4445 180)
			(size 0.1524 0.1524)
			(layers "F.Cu" "F.Mask" "F.Paste")
			(net "PCIE_TX_P71")
			(options
				(clearance outline)
				(anchor circle)
			)
			(primitives
				(gr_poly
					(pts
						(arc
							(start 0.3048 -0.2032)
							(mid 0.275042 -0.275042)
							(end 0.2032 -0.3048)
						)
						(arc
							(start -0.2032 -0.3048)
							(mid -0.275042 -0.275042)
							(end -0.3048 -0.2032)
						)
						(arc
							(start -0.3048 0.2032)
							(mid -0.275042 0.275042)
							(end -0.2032 0.3048)
						)
						(arc
							(start 0.2032 0.3048)
							(mid 0.275042 0.275042)
							(end 0.3048 0.2032)
						)
					)
					(width 0)
					(fill yes)
				)
			)
		)
	)
	(footprint ""
		(layer "F.Cu")
		(at 53.721 -136.779 90)
		(property "Reference" "R154"
			(at 0 0 90)
			(layer "F.SilkS")
			(hide yes)
			(effects
				(font
					(size 1.27 1.27)
				)
			)
		)
		(property "Value" "4K7R2F-GP"
			(at 0.064008 -3.993896 90)
			(unlocked yes)
			(layer "F.Fab")
			(hide yes)
			(effects
				(font
					(size 1.016 1.016)
					(thickness 0.1524)
				)
			)
		)
		(property "Device Type" "R402H16"
			(at 0.064008 -5.517896 90)
			(unlocked yes)
			(layer "F.Fab")
			(hide yes)
			(effects
				(font
					(size 1.016 1.016)
					(thickness 0.1524)
				)
			)
		)
		(duplicate_pad_numbers_are_jumpers no)
		(fp_line
			(start 0.508 -0.9398)
			(end -0.508 -0.9398)
			(stroke
				(width 0.1524)
				(type default)
			)
			(layer "F.SilkS")
		)
		(fp_line
			(start -0.508 -0.9398)
			(end -0.508 0.9398)
			(stroke
				(width 0.1524)
				(type default)
			)
			(layer "F.SilkS")
		)
		(fp_rect
			(start -0.508 0.9398)
			(end 0.508 -0.9398)
			(stroke
				(width 0)
				(type default)
			)
			(fill no)
			(layer "F.CrtYd")
		)
		(fp_rect
			(start -0.508 0.9398)
			(end 0.508 -0.9398)
			(stroke
				(width 0)
				(type default)
			)
			(fill no)
			(layer "F.Fab")
		)
		(pad "1" smd custom
			(at 0 -0.4445 90)
			(size 0.1397 0.1397)
			(layers "F.Cu" "F.Mask" "F.Paste")
			(net "CBL_PRSNT_N_6")
			(options
				(clearance outline)
				(anchor circle)
			)
			(primitives
				(gr_poly
					(pts
						(arc
							(start -0.1778 -0.2794)
							(mid -0.249642 -0.249642)
							(end -0.2794 -0.1778)
						)
						(arc
							(start -0.2794 0.1778)
							(mid -0.249642 0.249642)
							(end -0.1778 0.2794)
						)
						(arc
							(start 0.1778 0.2794)
							(mid 0.249642 0.249642)
							(end 0.2794 0.1778)
						)
						(arc
							(start 0.2794 -0.1778)
							(mid 0.249642 -0.249642)
							(end 0.1778 -0.2794)
						)
					)
					(width 0)
					(fill yes)
				)
			)
		)
		(pad "2" smd custom
			(at 0 0.4445 90)
			(size 0.1397 0.1397)
			(layers "F.Cu" "F.Mask" "F.Paste")
			(net "P3V3_STBY")
			(options
				(clearance outline)
				(anchor circle)
			)
			(primitives
				(gr_poly
					(pts
						(arc
							(start -0.1778 -0.2794)
							(mid -0.249642 -0.249642)
							(end -0.2794 -0.1778)
						)
						(arc
							(start -0.2794 0.1778)
							(mid -0.249642 0.249642)
							(end -0.1778 0.2794)
						)
						(arc
							(start 0.1778 0.2794)
							(mid 0.249642 0.249642)
							(end 0.2794 0.1778)
						)
						(arc
							(start 0.2794 -0.1778)
							(mid 0.249642 -0.249642)
							(end 0.1778 -0.2794)
						)
					)
					(width 0)
					(fill yes)
				)
			)
		)
	)
	(footprint ""
		(layer "F.Cu")
		(at 263.398 -26.289 180)
		(property "Reference" "R779"
			(at 0 0 180)
			(layer "F.SilkS")
			(hide yes)
			(effects
				(font
					(size 1.27 1.27)
				)
			)
		)
		(property "Value" "2KR2F-3-GP"
			(at 0.064008 -3.993896 180)
			(unlocked yes)
			(layer "F.Fab")
			(hide yes)
			(effects
				(font
					(size 1.016 1.016)
					(thickness 0.1524)
				)
			)
		)
		(property "Device Type" "R402H16"
			(at 0.064008 -5.517896 180)
			(unlocked yes)
			(layer "F.Fab")
			(hide yes)
			(effects
				(font
					(size 1.016 1.016)
					(thickness 0.1524)
				)
			)
		)
		(duplicate_pad_numbers_are_jumpers no)
		(fp_line
			(start 0.508 -0.9398)
			(end -0.508 -0.9398)
			(stroke
				(width 0.1524)
				(type default)
			)
			(layer "F.SilkS")
		)
		(fp_line
			(start -0.508 -0.9398)
			(end -0.508 0.9398)
			(stroke
				(width 0.1524)
				(type default)
			)
			(layer "F.SilkS")
		)
		(fp_rect
			(start -0.508 0.9398)
			(end 0.508 -0.9398)
			(stroke
				(width 0)
				(type default)
			)
			(fill no)
			(layer "F.CrtYd")
		)
		(fp_rect
			(start -0.508 0.9398)
			(end 0.508 -0.9398)
			(stroke
				(width 0)
				(type default)
			)
			(fill no)
			(layer "F.Fab")
		)
		(pad "1" smd custom
			(at 0 -0.4445 180)
			(size 0.1397 0.1397)
			(layers "F.Cu" "F.Mask" "F.Paste")
			(net "P3V3_GPIO")
			(options
				(clearance outline)
				(anchor circle)
			)
			(primitives
				(gr_poly
					(pts
						(arc
							(start -0.1778 -0.2794)
							(mid -0.249642 -0.249642)
							(end -0.2794 -0.1778)
						)
						(arc
							(start -0.2794 0.1778)
							(mid -0.249642 0.249642)
							(end -0.1778 0.2794)
						)
						(arc
							(start 0.1778 0.2794)
							(mid 0.249642 0.249642)
							(end 0.2794 0.1778)
						)
						(arc
							(start 0.2794 -0.1778)
							(mid 0.249642 -0.249642)
							(end 0.1778 -0.2794)
						)
					)
					(width 0)
					(fill yes)
				)
			)
		)
		(pad "2" smd custom
			(at 0 0.4445 180)
			(size 0.1397 0.1397)
			(layers "F.Cu" "F.Mask" "F.Paste")
			(net "TWI_SCL3")
			(options
				(clearance outline)
				(anchor circle)
			)
			(primitives
				(gr_poly
					(pts
						(arc
							(start -0.1778 -0.2794)
							(mid -0.249642 -0.249642)
							(end -0.2794 -0.1778)
						)
						(arc
							(start -0.2794 0.1778)
							(mid -0.249642 0.249642)
							(end -0.1778 0.2794)
						)
						(arc
							(start 0.1778 0.2794)
							(mid 0.249642 0.249642)
							(end 0.2794 0.1778)
						)
						(arc
							(start 0.2794 -0.1778)
							(mid 0.249642 -0.249642)
							(end 0.1778 -0.2794)
						)
					)
					(width 0)
					(fill yes)
				)
			)
		)
	)
	(footprint ""
		(layer "F.Cu")
		(at 53.7464 -125.5776 -90)
		(property "Reference" "R803"
			(at 0 0 270)
			(layer "F.SilkS")
			(hide yes)
			(effects
				(font
					(size 1.27 1.27)
				)
			)
		)
		(property "Value" "4K7R2F-GP"
			(at 0.064008 -3.993896 270)
			(unlocked yes)
			(layer "F.Fab")
			(hide yes)
			(effects
				(font
					(size 1.016 1.016)
					(thickness 0.1524)
				)
			)
		)
		(property "Device Type" "R402H16"
			(at 0.064008 -5.517896 270)
			(unlocked yes)
			(layer "F.Fab")
			(hide yes)
			(effects
				(font
					(size 1.016 1.016)
					(thickness 0.1524)
				)
			)
		)
		(duplicate_pad_numbers_are_jumpers no)
		(fp_line
			(start -0.508 -0.9398)
			(end -0.508 0.9398)
			(stroke
				(width 0.1524)
				(type default)
			)
			(layer "F.SilkS")
		)
		(fp_line
			(start 0.508 -0.9398)
			(end -0.508 -0.9398)
			(stroke
				(width 0.1524)
				(type default)
			)
			(layer "F.SilkS")
		)
		(fp_rect
			(start -0.508 0.9398)
			(end 0.508 -0.9398)
			(stroke
				(width 0)
				(type default)
			)
			(fill no)
			(layer "F.CrtYd")
		)
		(fp_rect
			(start -0.508 0.9398)
			(end 0.508 -0.9398)
			(stroke
				(width 0)
				(type default)
			)
			(fill no)
			(layer "F.Fab")
		)
		(pad "1" smd custom
			(at 0 -0.4445 270)
			(size 0.1397 0.1397)
			(layers "F.Cu" "F.Mask" "F.Paste")
			(net "P3V3_STBY")
			(options
				(clearance outline)
				(anchor circle)
			)
			(primitives
				(gr_poly
					(pts
						(arc
							(start -0.1778 -0.2794)
							(mid -0.249642 -0.249642)
							(end -0.2794 -0.1778)
						)
						(arc
							(start -0.2794 0.1778)
							(mid -0.249642 0.249642)
							(end -0.1778 0.2794)
						)
						(arc
							(start 0.1778 0.2794)
							(mid 0.249642 0.249642)
							(end 0.2794 0.1778)
						)
						(arc
							(start 0.2794 -0.1778)
							(mid 0.249642 -0.249642)
							(end 0.1778 -0.2794)
						)
					)
					(width 0)
					(fill yes)
				)
			)
		)
		(pad "2" smd custom
			(at 0 0.4445 270)
			(size 0.1397 0.1397)
			(layers "F.Cu" "F.Mask" "F.Paste")
			(net "JTAG_BMC_TMS")
			(options
				(clearance outline)
				(anchor circle)
			)
			(primitives
				(gr_poly
					(pts
						(arc
							(start -0.1778 -0.2794)
							(mid -0.249642 -0.249642)
							(end -0.2794 -0.1778)
						)
						(arc
							(start -0.2794 0.1778)
							(mid -0.249642 0.249642)
							(end -0.1778 0.2794)
						)
						(arc
							(start 0.1778 0.2794)
							(mid 0.249642 0.249642)
							(end 0.2794 0.1778)
						)
						(arc
							(start 0.2794 -0.1778)
							(mid 0.249642 -0.249642)
							(end 0.1778 -0.2794)
						)
					)
					(width 0)
					(fill yes)
				)
			)
		)
	)
	(footprint ""
		(layer "F.Cu")
		(at 47.117 -145.415 180)
		(property "Reference" "R228"
			(at 0 0 180)
			(layer "F.SilkS")
			(hide yes)
			(effects
				(font
					(size 1.27 1.27)
				)
			)
		)
		(property "Value" "4K7R2F-GP"
			(at 0.064008 -3.993896 180)
			(unlocked yes)
			(layer "F.Fab")
			(hide yes)
			(effects
				(font
					(size 1.016 1.016)
					(thickness 0.1524)
				)
			)
		)
		(property "Device Type" "R402H16"
			(at 0.064008 -5.517896 180)
			(unlocked yes)
			(layer "F.Fab")
			(hide yes)
			(effects
				(font
					(size 1.016 1.016)
					(thickness 0.1524)
				)
			)
		)
		(duplicate_pad_numbers_are_jumpers no)
		(fp_line
			(start 0.508 -0.9398)
			(end -0.508 -0.9398)
			(stroke
				(width 0.1524)
				(type default)
			)
			(layer "F.SilkS")
		)
		(fp_line
			(start -0.508 -0.9398)
			(end -0.508 0.9398)
			(stroke
				(width 0.1524)
				(type default)
			)
			(layer "F.SilkS")
		)
		(fp_rect
			(start -0.508 0.9398)
			(end 0.508 -0.9398)
			(stroke
				(width 0)
				(type default)
			)
			(fill no)
			(layer "F.CrtYd")
		)
		(fp_rect
			(start -0.508 0.9398)
			(end 0.508 -0.9398)
			(stroke
				(width 0)
				(type default)
			)
			(fill no)
			(layer "F.Fab")
		)
		(pad "1" smd custom
			(at 0 -0.4445 180)
			(size 0.1397 0.1397)
			(layers "F.Cu" "F.Mask" "F.Paste")
			(net "PEER_BMC_HB")
			(options
				(clearance outline)
				(anchor circle)
			)
			(primitives
				(gr_poly
					(pts
						(arc
							(start -0.1778 -0.2794)
							(mid -0.249642 -0.249642)
							(end -0.2794 -0.1778)
						)
						(arc
							(start -0.2794 0.1778)
							(mid -0.249642 0.249642)
							(end -0.1778 0.2794)
						)
						(arc
							(start 0.1778 0.2794)
							(mid 0.249642 0.249642)
							(end 0.2794 0.1778)
						)
						(arc
							(start 0.2794 -0.1778)
							(mid 0.249642 -0.249642)
							(end 0.1778 -0.2794)
						)
					)
					(width 0)
					(fill yes)
				)
			)
		)
		(pad "2" smd custom
			(at 0 0.4445 180)
			(size 0.1397 0.1397)
			(layers "F.Cu" "F.Mask" "F.Paste")
			(net "P3V3_STBY")
			(options
				(clearance outline)
				(anchor circle)
			)
			(primitives
				(gr_poly
					(pts
						(arc
							(start -0.1778 -0.2794)
							(mid -0.249642 -0.249642)
							(end -0.2794 -0.1778)
						)
						(arc
							(start -0.2794 0.1778)
							(mid -0.249642 0.249642)
							(end -0.1778 0.2794)
						)
						(arc
							(start 0.1778 0.2794)
							(mid 0.249642 0.249642)
							(end 0.2794 0.1778)
						)
						(arc
							(start 0.2794 -0.1778)
							(mid 0.249642 -0.249642)
							(end 0.1778 -0.2794)
						)
					)
					(width 0)
					(fill yes)
				)
			)
		)
	)
)
